(kicad_pcb
	(version 20221018)
	(generator pcbnew)
	(general
    (thickness 1.7403)
  )
	(paper "A4")
	(title_block
    (title "Data Center RDIMM DDR4 Tester")
    (date "2024-09-30")
    (rev "1.2.4")
		(comment 9 "footprints 259-265 of 690")
	)
	(layers
    (0 "F.Cu" signal)
    (1 "In1.Cu" power)
    (2 "In2.Cu" signal)
    (3 "In3.Cu" power)
    (4 "In4.Cu" power)
    (5 "In5.Cu" signal)
    (6 "In6.Cu" power)
    (7 "In7.Cu" signal)
    (8 "In8.Cu" power)
    (9 "In9.Cu" signal)
    (10 "In10.Cu" power)
    (31 "B.Cu" signal)
    (32 "B.Adhes" user "B.Adhesive")
    (33 "F.Adhes" user "F.Adhesive")
    (34 "B.Paste" user)
    (35 "F.Paste" user)
    (36 "B.SilkS" user "B.Silkscreen")
    (37 "F.SilkS" user "F.Silkscreen")
    (38 "B.Mask" user)
    (39 "F.Mask" user)
    (40 "Dwgs.User" user "User.Drawings")
    (41 "Cmts.User" user "User.Comments")
    (42 "Eco1.User" user "User.Eco1")
    (43 "Eco2.User" user "User.Eco2")
    (44 "Edge.Cuts" user)
    (45 "Margin" user)
    (46 "B.CrtYd" user "B.Courtyard")
    (47 "F.CrtYd" user "F.Courtyard")
    (48 "B.Fab" user)
    (49 "F.Fab" user)
  )
	(footprint "data-center-rdimm-ddr4-tester-footprints:R_0402_1005Metric" (layer "F.Cu")
    (at 256.2 90.3)
    (descr "Resistor SMD 0402")
    (tags "resistor SMD 0402")
    (property "Author" "Antmicro")
    (property "License" "Apache-2.0")
    (property "MPN" "CR0402-FX-4701GLF")
    (property "Manufacturer" "Bourns")
    (property "Sheetfile" "fmc_hpc.kicad_sch")
    (property "Sheetname" "FMC HPC")
    (property "Tolerance" "1%")
    (property "Val" "4k7")
    (property "ki_description" "4k7 resistor in 0402 package with 1% tolerance")
    (attr smd)
    (fp_text reference "R155" (at 0.66 0.35) (layer "F.SilkS")
        (effects (font (size 0.7 0.7) (thickness 0.15)) (justify left bottom))
    )
    (fp_text value "R_4k7_0402" (at 0 1.4) (layer "F.Fab") hide
        (effects (font (size 0.7 0.7) (thickness 0.15)) (justify left bottom))
    )
    (fp_text user "${REFERENCE}" (at -0.95 3.168) (layer "F.Fab") hide
        (effects (font (size 0.7 0.7) (thickness 0.15)) (justify left bottom))
    )
    (fp_text user "License: Apache-2.0" (at -0.95 5.169) (layer "F.Fab") hide
        (effects (font (size 0.7 0.7) (thickness 0.15)) (justify left bottom))
    )
    (fp_text user "Author: Antmicro" (at -0.95 4.169) (layer "F.Fab") hide
        (effects (font (size 0.7 0.7) (thickness 0.15)) (justify left bottom))
    )
    (fp_rect (start -0.93 -0.47) (end 0.93 0.47)
      (stroke (width 0.05) (type solid)) (fill none) (layer "F.CrtYd"))
    (fp_rect (start -0.5 -0.25) (end 0.5 0.25)
      (stroke (width 0.15) (type solid)) (fill none) (layer "F.Fab"))
    (pad "1" smd roundrect (at -0.485 0) (size 0.59 0.64) (layers "F.Cu" "F.Paste" "F.Mask") (roundrect_rratio 0.25)
      (net 143 "3V3_SYS") (pintype "passive"))
    (pad "2" smd roundrect (at 0.485 0) (size 0.59 0.64) (layers "F.Cu" "F.Paste" "F.Mask") (roundrect_rratio 0.25)
      (net 907 "FMC_SCL_3V3") (pintype "passive"))
  )
	(footprint "data-center-rdimm-ddr4-tester-footprints:R_0402_1005Metric" (layer "F.Cu")
    (at 154.2 127.515 -90)
    (descr "Resistor SMD 0402")
    (tags "resistor SMD 0402")
    (property "Author" "Antmicro")
    (property "License" "Apache-2.0")
    (property "MPN" "CR0402-FX-3300GLF")
    (property "Manufacturer" "Bourns")
    (property "Sheetfile" "interfaces.kicad_sch")
    (property "Sheetname" "Interfaces")
    (property "Tolerance" "1%")
    (property "Val" "330R")
    (property "ki_description" "330R resistor in 0402 package with 1% tolerance")
    (attr smd)
    (fp_text reference "R125" (at 1.035 -1.24 -90) (layer "F.SilkS")
        (effects (font (size 0.7 0.7) (thickness 0.15)) (justify left bottom))
    )
    (fp_text value "R_330R_0402" (at 0 1.4 -90) (layer "F.Fab") hide
        (effects (font (size 0.7 0.7) (thickness 0.15)) (justify left bottom))
    )
    (fp_text user "${REFERENCE}" (at -0.95 3.168 -90) (layer "F.Fab") hide
        (effects (font (size 0.7 0.7) (thickness 0.15)) (justify left bottom))
    )
    (fp_text user "Author: Antmicro" (at -0.95 4.169 -90) (layer "F.Fab") hide
        (effects (font (size 0.7 0.7) (thickness 0.15)) (justify left bottom))
    )
    (fp_text user "License: Apache-2.0" (at -0.95 5.169 -90) (layer "F.Fab") hide
        (effects (font (size 0.7 0.7) (thickness 0.15)) (justify left bottom))
    )
    (fp_rect (start -0.93 -0.47) (end 0.93 0.47)
      (stroke (width 0.05) (type solid)) (fill none) (layer "F.CrtYd"))
    (fp_rect (start -0.5 -0.25) (end 0.5 0.25)
      (stroke (width 0.15) (type solid)) (fill none) (layer "F.Fab"))
    (pad "1" smd roundrect (at -0.485 0 270) (size 0.59 0.64) (layers "F.Cu" "F.Paste" "F.Mask") (roundrect_rratio 0.25)
      (net 9 "GND") (pintype "passive"))
    (pad "2" smd roundrect (at 0.485 0 270) (size 0.59 0.64) (layers "F.Cu" "F.Paste" "F.Mask") (roundrect_rratio 0.25)
      (net 862 "GNDS") (pintype "passive"))
  )
	(footprint "data-center-rdimm-ddr4-tester-footprints:C_0402_1005Metric" (layer "F.Cu")
    (at 256.18 84.261)
    (descr "Capacitor SMD 0402")
    (tags "capacitor SMD 0402")
    (property "Author" "Antmicro")
    (property "Dielectric" "X5R")
    (property "License" "Apache-2.0")
    (property "MPN" "GRM155R61H104KE14D")
    (property "Manufacturer" "Murata")
    (property "Sheetfile" "fmc_hpc.kicad_sch")
    (property "Sheetname" "FMC HPC")
    (property "Val" "100n")
    (property "Voltage" "50V")
    (property "ki_description" " ")
    (attr smd)
    (fp_text reference "C274" (at 0.69 0.409) (layer "F.SilkS")
        (effects (font (size 0.7 0.7) (thickness 0.15)) (justify left bottom))
    )
    (fp_text value "C_100n_0402" (at 0 1.4) (layer "F.Fab") hide
        (effects (font (size 0.7 0.7) (thickness 0.15)) (justify left bottom))
    )
    (fp_text user "License: Apache-2.0" (at -0.932 5.17) (layer "F.Fab") hide
        (effects (font (size 0.7 0.7) (thickness 0.15)) (justify left bottom))
    )
    (fp_text user "Author: Antmicro" (at -0.932 4.17) (layer "F.Fab") hide
        (effects (font (size 0.7 0.7) (thickness 0.15)) (justify left bottom))
    )
    (fp_text user "${REFERENCE}" (at -0.932 3.168) (layer "F.Fab") hide
        (effects (font (size 0.7 0.7) (thickness 0.15)) (justify left bottom))
    )
    (fp_rect (start -0.94 -0.47) (end 0.94 0.47)
      (stroke (width 0.05) (type solid)) (fill none) (layer "F.CrtYd"))
    (fp_rect (start -0.499 -0.249) (end 0.499 0.249)
      (stroke (width 0.15) (type solid)) (fill none) (layer "F.Fab"))
    (pad "1" smd roundrect (at -0.484 0) (size 0.59 0.64) (layers "F.Cu" "F.Paste" "F.Mask") (roundrect_rratio 0.25)
      (net 525 "/FMC HPC/GTX_TX7_C_N") (pintype "passive"))
    (pad "2" smd roundrect (at 0.484 0) (size 0.59 0.64) (layers "F.Cu" "F.Paste" "F.Mask") (roundrect_rratio 0.25)
      (net 526 "GTX_TX7_N") (pintype "passive"))
  )
	(footprint "data-center-rdimm-ddr4-tester-footprints:PinHeader_2x7_P2mm_SMD_Shrouded_no-locator" (layer "F.Cu")
    (at 235.68 79.45 90)
    (descr "Pin Header 2x7 SMD Shrouded no-locator")
    (property "Author" "Antmicro")
    (property "DNP" "DNP")
    (property "License" "Apache-2.0")
    (property "MPN" "878321412")
    (property "Manufacturer" "Molex")
    (property "Sheetfile" "config-spi.kicad_sch")
    (property "Sheetname" "Config SPI flash")
    (property "dnp" "")
    (property "exclude_from_bom" "")
    (property "ki_description" "Pin Header, Signal, Wire-to-Board, 2 mm, 2 Rows, 14 Contacts, Surface Mount Straight")
    (property "ki_keywords" "PINSTRIP, HEADER ")
    (attr exclude_from_pos_files exclude_from_bom)
    (fp_text reference "J1" (at 8.86 -3.48) (layer "F.SilkS")
        (effects (font (size 0.7 0.7) (thickness 0.15)) (justify left bottom))
    )
    (fp_text value "PinHeader_2x7_P2mm_SMD_Shrouded_no-locator" (at 0 5.038 90) (layer "F.Fab")
        (effects (font (size 0.7 0.7) (thickness 0.15)) (justify left bottom))
    )
    (fp_text user "License: Apache-2.0" (at -8.933 7.038 90) (layer "F.Fab") hide
        (effects (font (size 0.7 0.7) (thickness 0.15)) (justify left bottom))
    )
    (fp_text user "Author: Antmicro" (at -8.933 8.237 90) (layer "F.Fab") hide
        (effects (font (size 0.7 0.7) (thickness 0.15)) (justify left bottom))
    )
    (fp_text user "${REFERENCE}" (at -8.933 9.438 90) (layer "F.Fab") hide
        (effects (font (size 0.7 0.7) (thickness 0.15)) (justify left bottom))
    )
    (fp_line (start -8.5 -3.301) (end -8.5 -2.801)
      (stroke (width 0.15) (type solid)) (layer "F.SilkS"))
    (fp_line (start -8.5 -3.301) (end -8 -3.301)
      (stroke (width 0.15) (type solid)) (layer "F.SilkS"))
    (fp_line (start -8.5 3.297) (end -8.5 2.797)
      (stroke (width 0.15) (type solid)) (layer "F.SilkS"))
    (fp_line (start -8.5 3.297) (end -8 3.297)
      (stroke (width 0.15) (type solid)) (layer "F.SilkS"))
    (fp_line (start -1.397 2.41) (end -1.397 2.91)
      (stroke (width 0.15) (type solid)) (layer "F.SilkS"))
    (fp_line (start -1.397 2.41) (end -0.9 2.41)
      (stroke (width 0.15) (type solid)) (layer "F.SilkS"))
    (fp_line (start 1.394 2.418) (end 0.897 2.418)
      (stroke (width 0.15) (type solid)) (layer "F.SilkS"))
    (fp_line (start 1.394 2.418) (end 1.394 2.918)
      (stroke (width 0.15) (type solid)) (layer "F.SilkS"))
    (fp_line (start 8.499 -3.301) (end 7.998 -3.301)
      (stroke (width 0.15) (type solid)) (layer "F.SilkS"))
    (fp_line (start 8.499 -3.301) (end 8.499 -2.801)
      (stroke (width 0.15) (type solid)) (layer "F.SilkS"))
    (fp_line (start 8.499 3.297) (end 7.998 3.297)
      (stroke (width 0.15) (type solid)) (layer "F.SilkS"))
    (fp_line (start 8.499 3.297) (end 8.499 2.797)
      (stroke (width 0.15) (type solid)) (layer "F.SilkS"))
    (fp_circle (center -6.8 3.4) (end -6.748 3.4)
      (stroke (width 0.15) (type solid)) (fill solid) (layer "F.SilkS"))
    (fp_rect (start -8.7 -3.7) (end 8.7 3.7)
      (stroke (width 0.05) (type solid)) (fill none) (layer "F.CrtYd"))
    (fp_line (start -8.325 -3.15) (end 8.323 -3.15)
      (stroke (width 0.15) (type solid)) (layer "F.Fab"))
    (fp_line (start -8.325 3.148) (end -8.325 -3.15)
      (stroke (width 0.15) (type solid)) (layer "F.Fab"))
    (fp_line (start -8.325 3.148) (end -1.397 3.148)
      (stroke (width 0.15) (type solid)) (layer "F.Fab"))
    (fp_line (start -1.397 2.41) (end -1.397 3.14)
      (stroke (width 0.15) (type solid)) (layer "F.Fab"))
    (fp_line (start -1.397 2.41) (end 1.394 2.41)
      (stroke (width 0.15) (type solid)) (layer "F.Fab"))
    (fp_line (start 1.394 2.41) (end 1.394 3.14)
      (stroke (width 0.15) (type solid)) (layer "F.Fab"))
    (fp_line (start 1.394 3.148) (end 8.323 3.148)
      (stroke (width 0.15) (type solid)) (layer "F.Fab"))
    (fp_line (start 8.323 3.148) (end 8.323 -3.15)
      (stroke (width 0.15) (type solid)) (layer "F.Fab"))
    (pad "1" smd rect (at -6 2.128 90) (size 1 2.75) (layers "F.Cu" "F.Paste" "F.Mask")
      (net 9 "GND") (pintype "passive"))
    (pad "2" smd rect (at -6 -2.13 90) (size 1 2.75) (layers "F.Cu" "F.Paste" "F.Mask")
      (net 143 "3V3_SYS") (pintype "passive"))
    (pad "3" smd rect (at -4 2.128 90) (size 1 2.75) (layers "F.Cu" "F.Paste" "F.Mask")
      (net 9 "GND") (pintype "passive"))
    (pad "4" smd rect (at -4 -2.13 90) (size 1 2.75) (layers "F.Cu" "F.Paste" "F.Mask")
      (net 13 "TMS_JTAG") (pintype "passive"))
    (pad "5" smd rect (at -2 2.128 90) (size 1 2.75) (layers "F.Cu" "F.Paste" "F.Mask")
      (net 9 "GND") (pintype "passive"))
    (pad "6" smd rect (at -2 -2.13 90) (size 1 2.75) (layers "F.Cu" "F.Paste" "F.Mask")
      (net 12 "TCK_JTAG") (pintype "passive"))
    (pad "7" smd rect (at 0 2.128 90) (size 1 2.75) (layers "F.Cu" "F.Paste" "F.Mask")
      (net 9 "GND") (pintype "passive"))
    (pad "8" smd rect (at 0 -2.13 90) (size 1 2.75) (layers "F.Cu" "F.Paste" "F.Mask")
      (net 15 "TDO_JTAG") (pintype "passive"))
    (pad "9" smd rect (at 1.999 2.128 90) (size 1 2.75) (layers "F.Cu" "F.Paste" "F.Mask")
      (net 9 "GND") (pintype "passive"))
    (pad "10" smd rect (at 1.999 -2.13 90) (size 1 2.75) (layers "F.Cu" "F.Paste" "F.Mask")
      (net 14 "TDI_JTAG") (pintype "passive"))
    (pad "11" smd rect (at 3.999 2.128 90) (size 1 2.75) (layers "F.Cu" "F.Paste" "F.Mask")
      (net 9 "GND") (pintype "passive"))
    (pad "12" smd rect (at 3.999 -2.13 90) (size 1 2.75) (layers "F.Cu" "F.Paste" "F.Mask")
      (net 380 "unconnected-(J1-Pad12)") (pintype "passive+no_connect"))
    (pad "13" smd rect (at 5.998 2.128 90) (size 1 2.75) (layers "F.Cu" "F.Paste" "F.Mask")
      (net 9 "GND") (pintype "passive"))
    (pad "14" smd rect (at 5.998 -2.13 90) (size 1 2.75) (layers "F.Cu" "F.Paste" "F.Mask")
      (net 379 "unconnected-(J1-Pad14)") (pintype "passive+no_connect"))
  )
	(footprint "data-center-rdimm-ddr4-tester-footprints:NetTie-2_SMD_Pad0.127mm" (layer "F.Cu")
    (at 144.77 83.7)
    (descr "Net tie, 2 pin, 0.127mm  SMD pads")
    (tags "net tie")
    (property "Author" "Antmicro")
    (property "License" "Apache-2.0")
    (property "MPN" "")
    (property "Manufacturer" "")
    (property "Sheetfile" "supply.kicad_sch")
    (property "Sheetname" "Supply")
    (property "ki_description" "Net tie, 2 pins")
    (property "ki_keywords" "net tie short")
    (attr through_hole exclude_from_pos_files)
    (net_tie_pad_groups "1, 2")
    (fp_text reference "NT14" (at -0.128 -1.345) (layer "F.SilkS") hide
        (effects (font (size 0.7 0.7) (thickness 0.15)) (justify left bottom))
    )
    (fp_text value "Net-Tie_2" (at 0 1.199) (layer "F.Fab") hide
        (effects (font (size 0.7 0.7) (thickness 0.15)) (justify left bottom))
    )
    (fp_text user "${REFERENCE}" (at -0.128 3.2) (layer "F.Fab") hide
        (effects (font (size 0.7 0.7) (thickness 0.15)) (justify left bottom))
    )
    (fp_text user "License: Apache-2.0" (at -0.128 5.6) (layer "F.Fab") hide
        (effects (font (size 0.7 0.7) (thickness 0.15)) (justify left bottom))
    )
    (fp_text user "Author: Antmicro" (at -0.128 4.4) (layer "F.Fab") hide
        (effects (font (size 0.7 0.7) (thickness 0.15)) (justify left bottom))
    )
    (fp_poly
      (pts
        (xy -0.0635 -0.0635)
        (xy 0.0625 -0.0635)
        (xy 0.0625 0.0635)
        (xy -0.0635 0.0635)
      )

      (stroke (width 0) (type solid)) (fill solid) (layer "F.Cu"))
    (pad "1" smd roundrect (at -0.127 0 180) (size 0.127 0.127) (layers "F.Cu") (roundrect_rratio 0.5)
      (chamfer_ratio 0) (chamfer top_left bottom_left)
      (net 845 "/Supply/1V0_SEN_-") (pinfunction "1") (pintype "passive"))
    (pad "2" smd roundrect (at 0.126 0) (size 0.127 0.127) (layers "F.Cu") (roundrect_rratio 0.5)
      (chamfer_ratio 0) (chamfer top_left bottom_left)
      (net 147 "1V0_SYS") (pinfunction "2") (pintype "passive"))
  )
	(footprint "data-center-rdimm-ddr4-tester-footprints:C_0402_1005Metric" (layer "F.Cu")
    (at 254.71 92.875 180)
    (descr "Capacitor SMD 0402")
    (tags "capacitor SMD 0402")
    (property "Author" "Antmicro")
    (property "Dielectric" "X5R")
    (property "License" "Apache-2.0")
    (property "MPN" "GRM155R61H104KE14D")
    (property "Manufacturer" "Murata")
    (property "Sheetfile" "fmc_hpc.kicad_sch")
    (property "Sheetname" "FMC HPC")
    (property "Val" "100n")
    (property "Voltage" "50V")
    (property "ki_description" " ")
    (attr smd)
    (fp_text reference "C263" (at -0.8 -0.385 180) (layer "F.SilkS")
        (effects (font (size 0.7 0.7) (thickness 0.15)) (justify left bottom))
    )
    (fp_text value "C_100n_0402" (at 0 1.4 180) (layer "F.Fab") hide
        (effects (font (size 0.7 0.7) (thickness 0.15)) (justify left bottom))
    )
    (fp_text user "Author: Antmicro" (at -0.932 4.17 180) (layer "F.Fab") hide
        (effects (font (size 0.7 0.7) (thickness 0.15)) (justify left bottom))
    )
    (fp_text user "${REFERENCE}" (at -0.932 3.168 180) (layer "F.Fab") hide
        (effects (font (size 0.7 0.7) (thickness 0.15)) (justify left bottom))
    )
    (fp_text user "License: Apache-2.0" (at -0.932 5.17 180) (layer "F.Fab") hide
        (effects (font (size 0.7 0.7) (thickness 0.15)) (justify left bottom))
    )
    (fp_rect (start -0.94 -0.47) (end 0.94 0.47)
      (stroke (width 0.05) (type solid)) (fill none) (layer "F.CrtYd"))
    (fp_rect (start -0.499 -0.249) (end 0.499 0.249)
      (stroke (width 0.15) (type solid)) (fill none) (layer "F.Fab"))
    (pad "1" smd roundrect (at -0.484 0 180) (size 0.59 0.64) (layers "F.Cu" "F.Paste" "F.Mask") (roundrect_rratio 0.25)
      (net 430 "/FMC HPC/GTX_TX2_C_P") (pintype "passive"))
    (pad "2" smd roundrect (at 0.484 0 180) (size 0.59 0.64) (layers "F.Cu" "F.Paste" "F.Mask") (roundrect_rratio 0.25)
      (net 431 "GTX_TX2_P") (pintype "passive"))
  )
	(footprint "data-center-rdimm-ddr4-tester-footprints:R_0201" (layer "F.Cu")
    (at 163.9 104.29 -90)
    (descr "Resistor SMD 0201")
    (tags "resistor SMD 0201")
    (property "Author" "Antmicro")
    (property "License" "Apache-2.0")
    (property "MPN" "CR0201-FX-0R00GLF")
    (property "Manufacturer" "Bourns")
    (property "Sheetfile" "ethernet.kicad_sch")
    (property "Sheetname" "Ethernet")
    (property "Tolerance" "1%")
    (property "Val" "0R")
    (property "ki_description" "0R resistor in 0201 package with 1% tolerance")
    (attr smd)
    (fp_text reference "R221" (at -0.63 -0.375 -90) (layer "F.SilkS")
        (effects (font (size 0.7 0.7) (thickness 0.15)) (justify left bottom))
    )
    (fp_text value "R_0R_0201" (at 0 1.25 -90) (layer "F.Fab") hide
        (effects (font (size 0.7 0.7) (thickness 0.15)) (justify left bottom))
    )
    (fp_text user "License: Apache-2.0" (at -0.71 4.25 -90) (layer "F.Fab") hide
        (effects (font (size 0.7 0.7) (thickness 0.15)) (justify left bottom))
    )
    (fp_text user "Author: Antmicro" (at -0.71 5.25 -90) (layer "F.Fab") hide
        (effects (font (size 0.7 0.7) (thickness 0.15)) (justify left bottom))
    )
    (fp_text user "${REFERENCE}" (at -0.71 3.25 -90) (layer "F.Fab") hide
        (effects (font (size 0.7 0.7) (thickness 0.15)) (justify left bottom))
    )
    (fp_rect (start -0.71 -0.36) (end 0.71 0.36)
      (stroke (width 0.05) (type solid)) (fill none) (layer "F.CrtYd"))
    (fp_rect (start -0.3 -0.15) (end 0.298 0.148)
      (stroke (width 0.15) (type solid)) (fill none) (layer "F.Fab"))
    (pad "" smd roundrect (at -0.346 0 270) (size 0.318 0.36) (layers "F.Paste") (roundrect_rratio 0.25))
    (pad "" smd roundrect (at 0.344 0 270) (size 0.318 0.36) (layers "F.Paste") (roundrect_rratio 0.25))
    (pad "1" smd roundrect (at -0.32 0 270) (size 0.46 0.4) (layers "F.Cu" "F.Mask") (roundrect_rratio 0.25)
      (net 16 "LED_LINK") (pintype "passive"))
    (pad "2" smd roundrect (at 0.32 0 270) (size 0.46 0.4) (layers "F.Cu" "F.Mask") (roundrect_rratio 0.25)
      (net 537 "INT_LED_LINK") (pintype "passive"))
  )
)
